# TIMECARD (Time Appliance Project (Time Card)) — schematic netlist excerpt (pin names and nets, part order shuffled) for the footprints in the layout excerpt that follows; sources: Cadence DE-HDL packaged netlist, KiCad conversion of R4006-B0001-02_R01.brd

R24  RESISTOR  4.7KOHM 1%  pkg SMC_0402R_H016  page 16 : \1\ = SEC_EEPROM_WP ; \2\ = SG
R243  RESISTOR  4.7KOHM 1%  pkg SMC_0402R_H016  page 29 : \1\ = XP3R3V ; \2\ = XP1R0V_PG

(kicad_pcb
	(version 20260206)
	(generator "pcbnew")
	(generator_version "10.0")
	(general
		(thickness 1.6)
		(legacy_teardrops no)
	)
	(paper "A4")
	(title_block
		(title "timecard-production-celestica-r4006 — R4006-B0001-02_R01.brd")
		(comment 1 "Time Appliance Project (Time Card) / footprints 681-682 of 1113")
	)
	(layers
		(0 "F.Cu" signal "TOP")
		(4 "In1.Cu" signal "L02_GND1")
		(6 "In2.Cu" signal "L03_SIG1")
		(8 "In3.Cu" signal "L04_GND2")
		(10 "In4.Cu" signal "L05_VCC1")
		(12 "In5.Cu" signal "L06_VCC2")
		(14 "In6.Cu" signal "L07_GND3")
		(16 "In7.Cu" signal "L08_SIG2")
		(18 "In8.Cu" signal "L09_GND4")
		(2 "B.Cu" signal "BOTTOM")
		(9 "F.Adhes" user "F.Adhesive")
		(11 "B.Adhes" user "B.Adhesive")
		(13 "F.Paste" user "Package Geometry/Pastemask Top")
		(15 "B.Paste" user "Package Geometry/Pastemask Bottom")
		(5 "F.SilkS" user "Ref Des/Silkscreen Top")
		(7 "B.SilkS" user "Ref Des/Silkscreen Bottom")
		(1 "F.Mask" user "Board Geometry/Soldermask Top")
		(3 "B.Mask" user "Board Geometry/Soldermask Bottom")
		(17 "Dwgs.User" user "User.Drawings")
		(19 "Cmts.User" user "User.Comments")
		(21 "Eco1.User" user "User.Eco1")
		(23 "Eco2.User" user "User.Eco2")
		(25 "Edge.Cuts" user "Board Geometry/Outline")
		(27 "Margin" user)
		(31 "F.CrtYd" user "Package Geometry/Place Bound Top")
		(29 "B.CrtYd" user "Package Geometry/Place Bound Bottom")
		(35 "F.Fab" user "Ref Des/Assembly Top")
		(33 "B.Fab" user "Ref Des/Assembly Bottom")
	)
	(footprint ""
		(layer "B.Cu")
		(at 22.0472 -18.034 180)
		(property "Reference" "R24"
			(at -2.3368 -0.03937 0)
			(unlocked yes)
			(layer "B.SilkS")
			(effects
				(font
					(size 0.7874 0.5842)
					(thickness 0.1524)
				)
				(justify mirror)
			)
		)
		(property "Value" "VAL*"
			(at -0.02032 2.13233 180)
			(unlocked yes)
			(layer "B.Fab")
			(hide yes)
			(effects
				(font
					(size 0.7874 0.5842)
					(thickness 0.1524)
				)
				(justify mirror)
			)
		)
		(property "Device Type" "RESISTOR-G155-14701-01,4.7KOHMA"
			(at -0.008382 1.210564 180)
			(unlocked yes)
			(layer "B.Fab")
			(hide yes)
			(effects
				(font
					(size 0.7874 0.5842)
					(thickness 0.1524)
				)
				(justify mirror)
			)
		)
		(property "User Part Number" "PARTNUM*"
			(at -0.02032 4.024884 180)
			(unlocked yes)
			(layer "Cmts.User")
			(hide yes)
			(effects
				(font
					(size 0.7874 0.5842)
					(thickness 0.1524)
				)
				(justify mirror)
			)
		)
		(property "Tolerance" "TOL*"
			(at -0.044704 3.05435 180)
			(unlocked yes)
			(layer "Cmts.User")
			(hide yes)
			(effects
				(font
					(size 0.7874 0.5842)
					(thickness 0.1524)
				)
				(justify mirror)
			)
		)
		(duplicate_pad_numbers_are_jumpers no)
		(fp_line
			(start 1.143 0.5588)
			(end -1.143 0.5588)
			(stroke
				(width 0.1)
				(type default)
			)
			(layer "B.SilkS")
		)
		(fp_line
			(start 1.143 -0.5588)
			(end 1.143 0.5588)
			(stroke
				(width 0.1)
				(type default)
			)
			(layer "B.SilkS")
		)
		(fp_line
			(start -1.143 0.5588)
			(end -1.143 -0.5588)
			(stroke
				(width 0.1)
				(type default)
			)
			(layer "B.SilkS")
		)
		(fp_line
			(start -1.143 -0.5588)
			(end 1.143 -0.5588)
			(stroke
				(width 0.1)
				(type default)
			)
			(layer "B.SilkS")
		)
		(fp_rect
			(start -1.143 0.5588)
			(end 1.143 -0.5588)
			(stroke
				(width 0)
				(type default)
			)
			(fill no)
			(layer "B.CrtYd")
		)
		(fp_line
			(start 0.508 0.3048)
			(end -0.508 0.3048)
			(stroke
				(width 0.1)
				(type default)
			)
			(layer "B.Fab")
		)
		(fp_line
			(start 0.508 -0.3048)
			(end 0.508 0.3048)
			(stroke
				(width 0.1)
				(type default)
			)
			(layer "B.Fab")
		)
		(fp_line
			(start -0.508 0.3048)
			(end -0.508 -0.3048)
			(stroke
				(width 0.1)
				(type default)
			)
			(layer "B.Fab")
		)
		(fp_line
			(start -0.508 -0.3048)
			(end 0.508 -0.3048)
			(stroke
				(width 0.1)
				(type default)
			)
			(layer "B.Fab")
		)
		(pad "1" smd rect
			(at 0.5334 0)
			(size 0.7112 0.6096)
			(layers "B.Cu" "B.Mask" "B.Paste")
			(net "SEC_EEPROM_WP")
		)
		(pad "2" smd rect
			(at -0.5334 0)
			(size 0.7112 0.6096)
			(layers "B.Cu" "B.Mask" "B.Paste")
			(net "SG")
		)
		(zone
			(layer "B.Cu")
			(hatch none 0.5)
			(connect_pads
				(clearance 0)
			)
			(min_thickness 0.25)
			(keepout
				(tracks allowed)
				(vias not_allowed)
				(pads allowed)
				(copperpour not_allowed)
				(footprints allowed)
			)
			(placement
				(enabled no)
				(sheetname "")
			)
			(fill
				(thermal_gap 0.5)
				(thermal_bridge_width 0.5)
				(island_removal_mode 0)
			)
			(polygon
				(pts
					(xy 22.1234 -18.3388) (xy 21.971 -18.3388) (xy 21.971 -17.7292) (xy 22.1234 -17.7292)
				)
			)
		)
	)
	(footprint ""
		(layer "B.Cu")
		(at 137.414 -57.785 180)
		(property "Reference" "R243"
			(at 0.381 -1.18237 0)
			(unlocked yes)
			(layer "B.SilkS")
			(effects
				(font
					(size 0.7874 0.5842)
					(thickness 0.1524)
				)
				(justify mirror)
			)
		)
		(property "Value" "VAL*"
			(at -0.02032 2.13233 180)
			(unlocked yes)
			(layer "B.Fab")
			(hide yes)
			(effects
				(font
					(size 0.7874 0.5842)
					(thickness 0.1524)
				)
				(justify mirror)
			)
		)
		(property "Device Type" "RESISTOR-G155-14701-01,4.7KOHMA"
			(at -0.008382 1.210564 180)
			(unlocked yes)
			(layer "B.Fab")
			(hide yes)
			(effects
				(font
					(size 0.7874 0.5842)
					(thickness 0.1524)
				)
				(justify mirror)
			)
		)
		(property "User Part Number" "PARTNUM*"
			(at -0.02032 4.024884 180)
			(unlocked yes)
			(layer "Cmts.User")
			(hide yes)
			(effects
				(font
					(size 0.7874 0.5842)
					(thickness 0.1524)
				)
				(justify mirror)
			)
		)
		(property "Tolerance" "TOL*"
			(at -0.044704 3.05435 180)
			(unlocked yes)
			(layer "Cmts.User")
			(hide yes)
			(effects
				(font
					(size 0.7874 0.5842)
					(thickness 0.1524)
				)
				(justify mirror)
			)
		)
		(duplicate_pad_numbers_are_jumpers no)
		(fp_line
			(start 1.143 0.5588)
			(end -1.143 0.5588)
			(stroke
				(width 0.1)
				(type default)
			)
			(layer "B.SilkS")
		)
		(fp_line
			(start 1.143 -0.5588)
			(end 1.143 0.5588)
			(stroke
				(width 0.1)
				(type default)
			)
			(layer "B.SilkS")
		)
		(fp_line
			(start -1.143 0.5588)
			(end -1.143 -0.5588)
			(stroke
				(width 0.1)
				(type default)
			)
			(layer "B.SilkS")
		)
		(fp_line
			(start -1.143 -0.5588)
			(end 1.143 -0.5588)
			(stroke
				(width 0.1)
				(type default)
			)
			(layer "B.SilkS")
		)
		(fp_rect
			(start -1.143 -0.5588)
			(end 1.143 0.5588)
			(stroke
				(width 0)
				(type default)
			)
			(fill no)
			(layer "B.CrtYd")
		)
		(fp_line
			(start 0.508 0.3048)
			(end -0.508 0.3048)
			(stroke
				(width 0.1)
				(type default)
			)
			(layer "B.Fab")
		)
		(fp_line
			(start 0.508 -0.3048)
			(end 0.508 0.3048)
			(stroke
				(width 0.1)
				(type default)
			)
			(layer "B.Fab")
		)
		(fp_line
			(start -0.508 0.3048)
			(end -0.508 -0.3048)
			(stroke
				(width 0.1)
				(type default)
			)
			(layer "B.Fab")
		)
		(fp_line
			(start -0.508 -0.3048)
			(end 0.508 -0.3048)
			(stroke
				(width 0.1)
				(type default)
			)
			(layer "B.Fab")
		)
		(pad "1" smd rect
			(at 0.5334 0)
			(size 0.7112 0.6096)
			(layers "B.Cu" "B.Mask" "B.Paste")
			(net "XP3R3V")
		)
		(pad "2" smd rect
			(at -0.5334 0)
			(size 0.7112 0.6096)
			(layers "B.Cu" "B.Mask" "B.Paste")
			(net "XP1R0V_PG")
		)
		(zone
			(layer "B.Cu")
			(hatch none 0.5)
			(connect_pads
				(clearance 0)
			)
			(min_thickness 0.25)
			(keepout
				(tracks allowed)
				(vias not_allowed)
				(pads allowed)
				(copperpour not_allowed)
				(footprints allowed)
			)
			(placement
				(enabled no)
				(sheetname "")
			)
			(fill
				(thermal_gap 0.5)
				(thermal_bridge_width 0.5)
				(island_removal_mode 0)
			)
			(polygon
				(pts
					(xy 137.4902 -57.4802) (xy 137.4902 -58.0898) (xy 137.3378 -58.0898) (xy 137.3378 -57.4802)
				)
			)
		)
	)
)
